(kicad_pcb
	(version 20260206)
	(generator "pcbnew")
	(generator_version "10.0")
	(general
		(thickness 1.6)
		(legacy_teardrops no)
	)
	(paper "A4")
	(title_block
		(title "03242023_DA0F0TMBIJ0_F0T_Motherboard_J_brd_V01_OCP.brd")
		(comment 1 "Grand Teton / footprints 2039-2046 of 6105")
	)
	(layers
		(0 "F.Cu" signal "TOP")
		(4 "In1.Cu" signal "GND")
		(6 "In2.Cu" signal "IN1")
		(8 "In3.Cu" signal "GND1")
		(10 "In4.Cu" signal "IN2")
		(12 "In5.Cu" signal "GND2")
		(14 "In6.Cu" signal "IN3")
		(16 "In7.Cu" signal "GND3")
		(18 "In8.Cu" signal "VCC")
		(20 "In9.Cu" signal "VCC1")
		(22 "In10.Cu" signal "GND4")
		(24 "In11.Cu" signal "IN4")
		(26 "In12.Cu" signal "GND5")
		(28 "In13.Cu" signal "IN5")
		(30 "In14.Cu" signal "GND6")
		(32 "In15.Cu" signal "IN6")
		(34 "In16.Cu" signal "GND7")
		(2 "B.Cu" signal "BOTTOM")
		(9 "F.Adhes" user "F.Adhesive")
		(11 "B.Adhes" user "B.Adhesive")
		(13 "F.Paste" user "Package Geometry/Pastemask Top")
		(15 "B.Paste" user "Package Geometry/Pastemask Bottom")
		(5 "F.SilkS" user "Ref Des/Silkscreen Top")
		(7 "B.SilkS" user "Ref Des/Silkscreen Bottom")
		(1 "F.Mask" user "Board Geometry/Soldermask Top")
		(3 "B.Mask" user "Board Geometry/Soldermask Bottom")
		(17 "Dwgs.User" user "User.Drawings")
		(19 "Cmts.User" user "User.Comments")
		(21 "Eco1.User" user "User.Eco1")
		(23 "Eco2.User" user "User.Eco2")
		(25 "Edge.Cuts" user "Board Geometry/Outline")
		(27 "Margin" user)
		(31 "F.CrtYd" user "Package Geometry/Place Bound Top")
		(29 "B.CrtYd" user "Package Geometry/Place Bound Bottom")
		(35 "F.Fab" user "Ref Des/Assembly Top")
		(33 "B.Fab" user "Ref Des/Assembly Bottom")
	)
	(footprint ""
		(layer "F.Cu")
		(at 33.410398 -390.10717 180)
		(property "Reference" "R3381"
			(at 0 0 180)
			(layer "F.SilkS")
			(hide yes)
			(effects
				(font
					(size 1.27 1.27)
				)
			)
		)
		(property "Value" ""
			(at 0 0 180)
			(layer "F.Fab")
			(effects
				(font
					(size 1.27 1.27)
				)
			)
		)
		(duplicate_pad_numbers_are_jumpers no)
		(fp_line
			(start 0.7874 0.4064)
			(end -0.7874 0.4064)
			(stroke
				(width 0.1524)
				(type default)
			)
			(layer "F.SilkS")
		)
		(fp_line
			(start 0.7874 -0.4064)
			(end 0.7874 0.4064)
			(stroke
				(width 0.1524)
				(type default)
			)
			(layer "F.SilkS")
		)
		(fp_line
			(start -0.7874 0.4064)
			(end -0.7874 -0.4064)
			(stroke
				(width 0.1524)
				(type default)
			)
			(layer "F.SilkS")
		)
		(fp_line
			(start -0.7874 -0.4064)
			(end 0.7874 -0.4064)
			(stroke
				(width 0.1524)
				(type default)
			)
			(layer "F.SilkS")
		)
		(fp_line
			(start 0.67945 0.3048)
			(end 0.120396 0.3048)
			(stroke
				(width 0.1)
				(type default)
			)
			(layer "F.Fab")
		)
		(fp_line
			(start 0.67945 -0.3048)
			(end 0.67945 0.3048)
			(stroke
				(width 0.1)
				(type default)
			)
			(layer "F.Fab")
		)
		(fp_line
			(start 0.12065 -0.2794)
			(end 0.12065 -0.3048)
			(stroke
				(width 0.1)
				(type default)
			)
			(layer "F.Fab")
		)
		(fp_line
			(start 0.12065 -0.3048)
			(end 0.67945 -0.3048)
			(stroke
				(width 0.1)
				(type default)
			)
			(layer "F.Fab")
		)
		(fp_line
			(start 0.120396 0.3048)
			(end 0.120396 0.2794)
			(stroke
				(width 0.1)
				(type default)
			)
			(layer "F.Fab")
		)
		(fp_line
			(start 0.120396 0.2794)
			(end -0.12065 0.2794)
			(stroke
				(width 0.1)
				(type default)
			)
			(layer "F.Fab")
		)
		(fp_line
			(start -0.12065 0.3048)
			(end -0.67945 0.3048)
			(stroke
				(width 0.1)
				(type default)
			)
			(layer "F.Fab")
		)
		(fp_line
			(start -0.12065 0.2794)
			(end -0.12065 0.3048)
			(stroke
				(width 0.1)
				(type default)
			)
			(layer "F.Fab")
		)
		(fp_line
			(start -0.12065 -0.2794)
			(end 0.12065 -0.2794)
			(stroke
				(width 0.1)
				(type default)
			)
			(layer "F.Fab")
		)
		(fp_line
			(start -0.12065 -0.305054)
			(end -0.12065 -0.2794)
			(stroke
				(width 0.1)
				(type default)
			)
			(layer "F.Fab")
		)
		(fp_line
			(start -0.67945 0.3048)
			(end -0.67945 -0.305054)
			(stroke
				(width 0.1)
				(type default)
			)
			(layer "F.Fab")
		)
		(fp_line
			(start -0.67945 -0.305054)
			(end -0.12065 -0.305054)
			(stroke
				(width 0.1)
				(type default)
			)
			(layer "F.Fab")
		)
		(pad "1" smd circle
			(at -0.40005 0 180)
			(size 0 0)
			(layers "F.Cu" "F.Mask" "F.Paste")
			(net "FM_P2E_BUF2_RXDET")
		)
		(pad "2" smd circle
			(at 0.40005 0 180)
			(size 0 0)
			(layers "F.Cu" "F.Mask" "F.Paste")
			(net "GND")
		)
	)
	(footprint ""
		(layer "F.Cu")
		(at 133.816852 -340.064598)
		(property "Reference" "PC506_P1_5"
			(at 0 0 0)
			(layer "F.SilkS")
			(hide yes)
			(effects
				(font
					(size 1.27 1.27)
				)
			)
		)
		(property "Value" ""
			(at 0 0 0)
			(layer "F.Fab")
			(effects
				(font
					(size 1.27 1.27)
				)
			)
		)
		(duplicate_pad_numbers_are_jumpers no)
		(fp_line
			(start -0.7874 -0.4064)
			(end 0.7874 -0.4064)
			(stroke
				(width 0.1524)
				(type default)
			)
			(layer "F.SilkS")
		)
		(fp_line
			(start -0.7874 0.4064)
			(end -0.7874 -0.4064)
			(stroke
				(width 0.1524)
				(type default)
			)
			(layer "F.SilkS")
		)
		(fp_line
			(start 0.7874 -0.4064)
			(end 0.7874 0.4064)
			(stroke
				(width 0.1524)
				(type default)
			)
			(layer "F.SilkS")
		)
		(fp_line
			(start 0.7874 0.4064)
			(end -0.7874 0.4064)
			(stroke
				(width 0.1524)
				(type default)
			)
			(layer "F.SilkS")
		)
		(fp_line
			(start -0.67945 -0.305054)
			(end -0.12065 -0.305054)
			(stroke
				(width 0.1)
				(type default)
			)
			(layer "F.Fab")
		)
		(fp_line
			(start -0.67945 0.3048)
			(end -0.67945 -0.305054)
			(stroke
				(width 0.1)
				(type default)
			)
			(layer "F.Fab")
		)
		(fp_line
			(start -0.12065 -0.305054)
			(end -0.12065 -0.2794)
			(stroke
				(width 0.1)
				(type default)
			)
			(layer "F.Fab")
		)
		(fp_line
			(start -0.12065 -0.2794)
			(end 0.12065 -0.2794)
			(stroke
				(width 0.1)
				(type default)
			)
			(layer "F.Fab")
		)
		(fp_line
			(start -0.12065 0.2794)
			(end -0.12065 0.3048)
			(stroke
				(width 0.1)
				(type default)
			)
			(layer "F.Fab")
		)
		(fp_line
			(start -0.12065 0.3048)
			(end -0.67945 0.3048)
			(stroke
				(width 0.1)
				(type default)
			)
			(layer "F.Fab")
		)
		(fp_line
			(start 0.120396 0.2794)
			(end -0.12065 0.2794)
			(stroke
				(width 0.1)
				(type default)
			)
			(layer "F.Fab")
		)
		(fp_line
			(start 0.120396 0.3048)
			(end 0.120396 0.2794)
			(stroke
				(width 0.1)
				(type default)
			)
			(layer "F.Fab")
		)
		(fp_line
			(start 0.12065 -0.3048)
			(end 0.67945 -0.3048)
			(stroke
				(width 0.1)
				(type default)
			)
			(layer "F.Fab")
		)
		(fp_line
			(start 0.12065 -0.2794)
			(end 0.12065 -0.3048)
			(stroke
				(width 0.1)
				(type default)
			)
			(layer "F.Fab")
		)
		(fp_line
			(start 0.67945 -0.3048)
			(end 0.67945 0.3048)
			(stroke
				(width 0.1)
				(type default)
			)
			(layer "F.Fab")
		)
		(fp_line
			(start 0.67945 0.3048)
			(end 0.120396 0.3048)
			(stroke
				(width 0.1)
				(type default)
			)
			(layer "F.Fab")
		)
		(pad "1" smd circle
			(at -0.40005 0)
			(size 0 0)
			(layers "F.Cu" "F.Mask" "F.Paste")
			(net "SW_P12V_PVCCIN_CPU1_FLT")
		)
		(pad "2" smd circle
			(at 0.40005 0)
			(size 0 0)
			(layers "F.Cu" "F.Mask" "F.Paste")
			(net "GND")
		)
	)
	(footprint ""
		(layer "F.Cu")
		(at 455.228452 -15.503398 180)
		(property "Reference" "PD102"
			(at -2.299716 -2.168652 0)
			(unlocked yes)
			(layer "F.SilkS")
			(effects
				(font
					(size 0.7874 0.5842)
					(thickness 0.1524)
				)
				(justify left)
			)
		)
		(property "Value" ""
			(at 0 0 180)
			(layer "F.Fab")
			(effects
				(font
					(size 1.27 1.27)
				)
			)
		)
		(duplicate_pad_numbers_are_jumpers no)
		(fp_line
			(start 4.107942 1.459992)
			(end -3.400044 1.459992)
			(stroke
				(width 0.1524)
				(type default)
			)
			(layer "F.SilkS")
		)
		(fp_line
			(start 4.107942 -1.459992)
			(end 4.107942 1.459992)
			(stroke
				(width 0.1524)
				(type default)
			)
			(layer "F.SilkS")
		)
		(fp_line
			(start -3.400044 1.459992)
			(end -3.400044 -1.459992)
			(stroke
				(width 0.1524)
				(type default)
			)
			(layer "F.SilkS")
		)
		(fp_line
			(start -3.400044 -1.459992)
			(end 4.107942 -1.459992)
			(stroke
				(width 0.1524)
				(type default)
			)
			(layer "F.SilkS")
		)
		(fp_rect
			(start 4.107942 -1.459992)
			(end 3.308096 1.459992)
			(stroke
				(width 0)
				(type default)
			)
			(fill yes)
			(layer "F.SilkS")
		)
		(fp_line
			(start 2.29997 1.459992)
			(end -2.29997 1.459992)
			(stroke
				(width 0.1)
				(type default)
			)
			(layer "F.Fab")
		)
		(fp_line
			(start 2.29997 -1.459992)
			(end 2.29997 1.459992)
			(stroke
				(width 0.1)
				(type default)
			)
			(layer "F.Fab")
		)
		(fp_line
			(start -2.29997 1.459992)
			(end -2.29997 -1.459992)
			(stroke
				(width 0.1)
				(type default)
			)
			(layer "F.Fab")
		)
		(fp_line
			(start -2.29997 -1.459992)
			(end 2.29997 -1.459992)
			(stroke
				(width 0.1)
				(type default)
			)
			(layer "F.Fab")
		)
		(fp_text user "-"
			(at 5.4102 0.29845 0)
			(unlocked yes)
			(layer "F.SilkS")
			(effects
				(font
					(size 1.905 1.4224)
					(thickness 0.1524)
				)
				(justify left)
			)
		)
		(fp_text user "+"
			(at -4.7752 -0.12065 180)
			(unlocked yes)
			(layer "F.SilkS")
			(effects
				(font
					(size 1.905 1.4224)
					(thickness 0.1524)
				)
				(justify left)
			)
		)
		(fp_text user "-"
			(at 5.4102 0.29845 0)
			(unlocked yes)
			(layer "F.Fab")
			(effects
				(font
					(size 1.905 1.4224)
					(thickness 0.1524)
				)
				(justify left)
			)
		)
		(fp_text user "+"
			(at -4.7752 -0.12065 180)
			(unlocked yes)
			(layer "F.Fab")
			(effects
				(font
					(size 1.905 1.4224)
					(thickness 0.1524)
				)
				(justify left)
			)
		)
		(pad "A" smd rect
			(at -1.999996 0 270)
			(size 1.7018 2.5146)
			(layers "F.Cu" "F.Mask" "F.Paste")
			(net "GND")
		)
		(pad "C" smd rect
			(at 1.999996 0 270)
			(size 1.7018 2.5146)
			(layers "F.Cu" "F.Mask" "F.Paste")
			(net "P12V_OCP_SFF")
		)
	)
	(footprint ""
		(layer "F.Cu")
		(at 389.902192 -76.171044 90)
		(property "Reference" "PC1232"
			(at 0 0 90)
			(layer "F.SilkS")
			(hide yes)
			(effects
				(font
					(size 1.27 1.27)
				)
			)
		)
		(property "Value" ""
			(at 0 0 90)
			(layer "F.Fab")
			(effects
				(font
					(size 1.27 1.27)
				)
			)
		)
		(duplicate_pad_numbers_are_jumpers no)
		(fp_line
			(start 1.524 -0.762)
			(end 1.524 0.762)
			(stroke
				(width 0.1524)
				(type default)
			)
			(layer "F.SilkS")
		)
		(fp_line
			(start -1.524 -0.762)
			(end 1.524 -0.762)
			(stroke
				(width 0.1524)
				(type default)
			)
			(layer "F.SilkS")
		)
		(fp_line
			(start 1.524 0.762)
			(end -1.524 0.762)
			(stroke
				(width 0.1524)
				(type default)
			)
			(layer "F.SilkS")
		)
		(fp_line
			(start -1.524 0.762)
			(end -1.524 -0.762)
			(stroke
				(width 0.1524)
				(type default)
			)
			(layer "F.SilkS")
		)
		(fp_line
			(start 1.1049 -0.724916)
			(end -1.1049 -0.724916)
			(stroke
				(width 0.1)
				(type default)
			)
			(layer "F.Fab")
		)
		(fp_line
			(start -1.1049 -0.724916)
			(end -1.1049 0.724916)
			(stroke
				(width 0.1)
				(type default)
			)
			(layer "F.Fab")
		)
		(fp_line
			(start 1.1049 0.724916)
			(end 1.1049 -0.724916)
			(stroke
				(width 0.1)
				(type default)
			)
			(layer "F.Fab")
		)
		(fp_line
			(start -1.1049 0.724916)
			(end 1.1049 0.724916)
			(stroke
				(width 0.1)
				(type default)
			)
			(layer "F.Fab")
		)
		(pad "1" smd rect
			(at -0.889 0 270)
			(size 1.016 1.27)
			(layers "F.Cu" "F.Mask" "F.Paste")
			(net "SW_P1V8_PCH_AUX_FLT")
		)
		(pad "2" smd rect
			(at 0.889 0 270)
			(size 1.016 1.27)
			(layers "F.Cu" "F.Mask" "F.Paste")
			(net "GND")
		)
	)
	(footprint ""
		(layer "F.Cu")
		(at 141.66088 -368.645948 -90)
		(property "Reference" "R1712"
			(at 0 0 270)
			(layer "F.SilkS")
			(hide yes)
			(effects
				(font
					(size 1.27 1.27)
				)
			)
		)
		(property "Value" ""
			(at 0 0 270)
			(layer "F.Fab")
			(effects
				(font
					(size 1.27 1.27)
				)
			)
		)
		(duplicate_pad_numbers_are_jumpers no)
		(fp_line
			(start -0.7874 0.4064)
			(end -0.7874 -0.4064)
			(stroke
				(width 0.1524)
				(type default)
			)
			(layer "F.SilkS")
		)
		(fp_line
			(start 0.7874 0.4064)
			(end -0.7874 0.4064)
			(stroke
				(width 0.1524)
				(type default)
			)
			(layer "F.SilkS")
		)
		(fp_line
			(start -0.7874 -0.4064)
			(end 0.7874 -0.4064)
			(stroke
				(width 0.1524)
				(type default)
			)
			(layer "F.SilkS")
		)
		(fp_line
			(start 0.7874 -0.4064)
			(end 0.7874 0.4064)
			(stroke
				(width 0.1524)
				(type default)
			)
			(layer "F.SilkS")
		)
		(fp_line
			(start -0.67945 0.3048)
			(end -0.67945 -0.305054)
			(stroke
				(width 0.1)
				(type default)
			)
			(layer "F.Fab")
		)
		(fp_line
			(start -0.12065 0.3048)
			(end -0.67945 0.3048)
			(stroke
				(width 0.1)
				(type default)
			)
			(layer "F.Fab")
		)
		(fp_line
			(start 0.120396 0.3048)
			(end 0.120396 0.2794)
			(stroke
				(width 0.1)
				(type default)
			)
			(layer "F.Fab")
		)
		(fp_line
			(start 0.67945 0.3048)
			(end 0.120396 0.3048)
			(stroke
				(width 0.1)
				(type default)
			)
			(layer "F.Fab")
		)
		(fp_line
			(start -0.12065 0.2794)
			(end -0.12065 0.3048)
			(stroke
				(width 0.1)
				(type default)
			)
			(layer "F.Fab")
		)
		(fp_line
			(start 0.120396 0.2794)
			(end -0.12065 0.2794)
			(stroke
				(width 0.1)
				(type default)
			)
			(layer "F.Fab")
		)
		(fp_line
			(start -0.12065 -0.2794)
			(end 0.12065 -0.2794)
			(stroke
				(width 0.1)
				(type default)
			)
			(layer "F.Fab")
		)
		(fp_line
			(start 0.12065 -0.2794)
			(end 0.12065 -0.3048)
			(stroke
				(width 0.1)
				(type default)
			)
			(layer "F.Fab")
		)
		(fp_line
			(start 0.12065 -0.3048)
			(end 0.67945 -0.3048)
			(stroke
				(width 0.1)
				(type default)
			)
			(layer "F.Fab")
		)
		(fp_line
			(start 0.67945 -0.3048)
			(end 0.67945 0.3048)
			(stroke
				(width 0.1)
				(type default)
			)
			(layer "F.Fab")
		)
		(fp_line
			(start -0.67945 -0.305054)
			(end -0.12065 -0.305054)
			(stroke
				(width 0.1)
				(type default)
			)
			(layer "F.Fab")
		)
		(fp_line
			(start -0.12065 -0.305054)
			(end -0.12065 -0.2794)
			(stroke
				(width 0.1)
				(type default)
			)
			(layer "F.Fab")
		)
		(pad "1" smd circle
			(at -0.40005 0 270)
			(size 0 0)
			(layers "F.Cu" "F.Mask" "F.Paste")
			(net "SMB_VR_3V3AUX_SDA_R3")
		)
		(pad "2" smd circle
			(at 0.40005 0 270)
			(size 0 0)
			(layers "F.Cu" "F.Mask" "F.Paste")
			(net "P3V3_AUX")
		)
	)
	(footprint ""
		(layer "F.Cu")
		(at 108.56722 -294.01008)
		(property "Reference" "C265"
			(at 0 0 0)
			(layer "F.SilkS")
			(hide yes)
			(effects
				(font
					(size 1.27 1.27)
				)
			)
		)
		(property "Value" ""
			(at 0 0 0)
			(layer "F.Fab")
			(effects
				(font
					(size 1.27 1.27)
				)
			)
		)
		(duplicate_pad_numbers_are_jumpers no)
		(fp_line
			(start -1.524 -0.762)
			(end 1.524 -0.762)
			(stroke
				(width 0.1524)
				(type default)
			)
			(layer "F.SilkS")
		)
		(fp_line
			(start -1.524 0.762)
			(end -1.524 -0.762)
			(stroke
				(width 0.1524)
				(type default)
			)
			(layer "F.SilkS")
		)
		(fp_line
			(start 1.524 -0.762)
			(end 1.524 0.762)
			(stroke
				(width 0.1524)
				(type default)
			)
			(layer "F.SilkS")
		)
		(fp_line
			(start 1.524 0.762)
			(end -1.524 0.762)
			(stroke
				(width 0.1524)
				(type default)
			)
			(layer "F.SilkS")
		)
		(fp_line
			(start -1.1049 -0.724916)
			(end -1.1049 0.724916)
			(stroke
				(width 0.1)
				(type default)
			)
			(layer "F.Fab")
		)
		(fp_line
			(start -1.1049 0.724916)
			(end 1.1049 0.724916)
			(stroke
				(width 0.1)
				(type default)
			)
			(layer "F.Fab")
		)
		(fp_line
			(start 1.1049 -0.724916)
			(end -1.1049 -0.724916)
			(stroke
				(width 0.1)
				(type default)
			)
			(layer "F.Fab")
		)
		(fp_line
			(start 1.1049 0.724916)
			(end 1.1049 -0.724916)
			(stroke
				(width 0.1)
				(type default)
			)
			(layer "F.Fab")
		)
		(pad "1" smd rect
			(at -0.889 0 180)
			(size 1.016 1.27)
			(layers "F.Cu" "F.Mask" "F.Paste")
			(net "PVCCIN_CPU1")
		)
		(pad "2" smd rect
			(at 0.889 0 180)
			(size 1.016 1.27)
			(layers "F.Cu" "F.Mask" "F.Paste")
			(net "GND")
		)
	)
	(footprint ""
		(layer "F.Cu")
		(at 70.382892 -47.049944)
		(property "Reference" "H31"
			(at -1.7272 -4.511548 0)
			(unlocked yes)
			(layer "B.SilkS")
			(effects
				(font
					(size 0.7874 0.5842)
					(thickness 0.1524)
				)
				(justify left mirror)
			)
		)
		(property "Value" ""
			(at 0 0 0)
			(layer "F.Fab")
			(effects
				(font
					(size 1.27 1.27)
				)
			)
		)
		(duplicate_pad_numbers_are_jumpers no)
		(pad "1" thru_hole circle
			(at 0 0)
			(size 4.5212 4.5212)
			(drill 3.81)
			(layers "*.Cu" "*.Mask")
			(remove_unused_layers no)
			(net "GND")
			(clearance -0.1016)
			(padstack
				(mode front_inner_back)
				(layer "Inner"
					(shape circle)
					(size 5.6134 5.6134)
					(clearance -0.6477)
				)
				(layer "B.Cu"
					(shape circle)
					(size 8.001 8.001)
					(clearance -1.8415)
				)
			)
		)
	)
	(footprint ""
		(layer "F.Cu")
		(at 55.090314 -144.267174)
		(property "Reference" "PC2949"
			(at 0 0 0)
			(layer "F.SilkS")
			(hide yes)
			(effects
				(font
					(size 1.27 1.27)
				)
			)
		)
		(property "Value" ""
			(at 0 0 0)
			(layer "F.Fab")
			(effects
				(font
					(size 1.27 1.27)
				)
			)
		)
		(duplicate_pad_numbers_are_jumpers no)
		(fp_line
			(start -0.7874 -0.4064)
			(end 0.7874 -0.4064)
			(stroke
				(width 0.1524)
				(type default)
			)
			(layer "F.SilkS")
		)
		(fp_line
			(start -0.7874 0.4064)
			(end -0.7874 -0.4064)
			(stroke
				(width 0.1524)
				(type default)
			)
			(layer "F.SilkS")
		)
		(fp_line
			(start 0.7874 -0.4064)
			(end 0.7874 0.4064)
			(stroke
				(width 0.1524)
				(type default)
			)
			(layer "F.SilkS")
		)
		(fp_line
			(start 0.7874 0.4064)
			(end -0.7874 0.4064)
			(stroke
				(width 0.1524)
				(type default)
			)
			(layer "F.SilkS")
		)
		(fp_line
			(start -0.67945 -0.305054)
			(end -0.12065 -0.305054)
			(stroke
				(width 0.1)
				(type default)
			)
			(layer "F.Fab")
		)
		(fp_line
			(start -0.67945 0.3048)
			(end -0.67945 -0.305054)
			(stroke
				(width 0.1)
				(type default)
			)
			(layer "F.Fab")
		)
		(fp_line
			(start -0.12065 -0.305054)
			(end -0.12065 -0.2794)
			(stroke
				(width 0.1)
				(type default)
			)
			(layer "F.Fab")
		)
		(fp_line
			(start -0.12065 -0.2794)
			(end 0.12065 -0.2794)
			(stroke
				(width 0.1)
				(type default)
			)
			(layer "F.Fab")
		)
		(fp_line
			(start -0.12065 0.2794)
			(end -0.12065 0.3048)
			(stroke
				(width 0.1)
				(type default)
			)
			(layer "F.Fab")
		)
		(fp_line
			(start -0.12065 0.3048)
			(end -0.67945 0.3048)
			(stroke
				(width 0.1)
				(type default)
			)
			(layer "F.Fab")
		)
		(fp_line
			(start 0.120396 0.2794)
			(end -0.12065 0.2794)
			(stroke
				(width 0.1)
				(type default)
			)
			(layer "F.Fab")
		)
		(fp_line
			(start 0.120396 0.3048)
			(end 0.120396 0.2794)
			(stroke
				(width 0.1)
				(type default)
			)
			(layer "F.Fab")
		)
		(fp_line
			(start 0.12065 -0.3048)
			(end 0.67945 -0.3048)
			(stroke
				(width 0.1)
				(type default)
			)
			(layer "F.Fab")
		)
		(fp_line
			(start 0.12065 -0.2794)
			(end 0.12065 -0.3048)
			(stroke
				(width 0.1)
				(type default)
			)
			(layer "F.Fab")
		)
		(fp_line
			(start 0.67945 -0.3048)
			(end 0.67945 0.3048)
			(stroke
				(width 0.1)
				(type default)
			)
			(layer "F.Fab")
		)
		(fp_line
			(start 0.67945 0.3048)
			(end 0.120396 0.3048)
			(stroke
				(width 0.1)
				(type default)
			)
			(layer "F.Fab")
		)
		(pad "1" smd circle
			(at -0.40005 0)
			(size 0 0)
			(layers "F.Cu" "F.Mask" "F.Paste")
			(net "PVCCFA_EHV_CPU1_PVCC")
		)
		(pad "2" smd circle
			(at 0.40005 0)
			(size 0 0)
			(layers "F.Cu" "F.Mask" "F.Paste")
			(net "GND")
		)
	)
)
